# S9S_MB_2U (Grand Teton) — schematic netlist excerpt (pin names and nets, part order shuffled) for the footprints in the layout excerpt that follows; sources: Cadence DE-HDL packaged netlist, KiCad conversion of 03242023_DA0F0TMBIJ0_F0T_Motherboard_J_brd_V01_OCP.brd

C388  Q_CAP  47UF 4V 20% X6S  pkg C0805  page 76 : A = PVCCIN_CPU0 ; B = GND
PR123  Q_RES  1K 1% EMPTY  pkg 0402LF  page 274 : A = PVCCINFAON_CPU0_VIN_CSNIN ; B = GND

DB11  TDR_3P  EMPTY  pkg TH2  page 309
  GND  = T1_GND
  IO1  = TDR_SE_50_OHM_IN4
  IO2  = TDR_SE_50_OHM_IN4

(kicad_pcb
	(version 20260206)
	(generator "pcbnew")
	(generator_version "10.0")
	(general
		(thickness 1.6)
		(legacy_teardrops no)
	)
	(paper "A4")
	(title_block
		(title "03242023_DA0F0TMBIJ0_F0T_Motherboard_J_brd_V01_OCP.brd")
		(comment 1 "Grand Teton / footprints 4993-4995 of 6105")
	)
	(layers
		(0 "F.Cu" signal "TOP")
		(4 "In1.Cu" signal "GND")
		(6 "In2.Cu" signal "IN1")
		(8 "In3.Cu" signal "GND1")
		(10 "In4.Cu" signal "IN2")
		(12 "In5.Cu" signal "GND2")
		(14 "In6.Cu" signal "IN3")
		(16 "In7.Cu" signal "GND3")
		(18 "In8.Cu" signal "VCC")
		(20 "In9.Cu" signal "VCC1")
		(22 "In10.Cu" signal "GND4")
		(24 "In11.Cu" signal "IN4")
		(26 "In12.Cu" signal "GND5")
		(28 "In13.Cu" signal "IN5")
		(30 "In14.Cu" signal "GND6")
		(32 "In15.Cu" signal "IN6")
		(34 "In16.Cu" signal "GND7")
		(2 "B.Cu" signal "BOTTOM")
		(9 "F.Adhes" user "F.Adhesive")
		(11 "B.Adhes" user "B.Adhesive")
		(13 "F.Paste" user "Package Geometry/Pastemask Top")
		(15 "B.Paste" user "Package Geometry/Pastemask Bottom")
		(5 "F.SilkS" user "Ref Des/Silkscreen Top")
		(7 "B.SilkS" user "Ref Des/Silkscreen Bottom")
		(1 "F.Mask" user "Board Geometry/Soldermask Top")
		(3 "B.Mask" user "Board Geometry/Soldermask Bottom")
		(17 "Dwgs.User" user "User.Drawings")
		(19 "Cmts.User" user "User.Comments")
		(21 "Eco1.User" user "User.Eco1")
		(23 "Eco2.User" user "User.Eco2")
		(25 "Edge.Cuts" user "Board Geometry/Outline")
		(27 "Margin" user)
		(31 "F.CrtYd" user "Package Geometry/Place Bound Top")
		(29 "B.CrtYd" user "Package Geometry/Place Bound Bottom")
		(35 "F.Fab" user "Ref Des/Assembly Top")
		(33 "B.Fab" user "Ref Des/Assembly Bottom")
	)
	(footprint ""
		(layer "B.Cu")
		(at 353.610418 -296.054526)
		(property "Reference" "C388"
			(at 0 0 0)
			(layer "B.SilkS")
			(hide yes)
			(effects
				(font
					(size 1.27 1.27)
				)
				(justify mirror)
			)
		)
		(property "Value" ""
			(at 0 0 0)
			(layer "B.Fab")
			(effects
				(font
					(size 1.27 1.27)
				)
				(justify mirror)
			)
		)
		(duplicate_pad_numbers_are_jumpers no)
		(fp_line
			(start -1.524 -0.762)
			(end -1.524 0.762)
			(stroke
				(width 0.1524)
				(type default)
			)
			(layer "B.SilkS")
		)
		(fp_line
			(start -1.524 0.762)
			(end 1.524 0.762)
			(stroke
				(width 0.1524)
				(type default)
			)
			(layer "B.SilkS")
		)
		(fp_line
			(start 1.524 -0.762)
			(end -1.524 -0.762)
			(stroke
				(width 0.1524)
				(type default)
			)
			(layer "B.SilkS")
		)
		(fp_line
			(start 1.524 0.762)
			(end 1.524 -0.762)
			(stroke
				(width 0.1524)
				(type default)
			)
			(layer "B.SilkS")
		)
		(fp_line
			(start -1.1049 -0.724916)
			(end 1.1049 -0.724916)
			(stroke
				(width 0.1)
				(type default)
			)
			(layer "B.Fab")
		)
		(fp_line
			(start -1.1049 0.724916)
			(end -1.1049 -0.724916)
			(stroke
				(width 0.1)
				(type default)
			)
			(layer "B.Fab")
		)
		(fp_line
			(start 1.1049 -0.724916)
			(end 1.1049 0.724916)
			(stroke
				(width 0.1)
				(type default)
			)
			(layer "B.Fab")
		)
		(fp_line
			(start 1.1049 0.724916)
			(end -1.1049 0.724916)
			(stroke
				(width 0.1)
				(type default)
			)
			(layer "B.Fab")
		)
		(pad "1" smd rect
			(at 0.889 0)
			(size 1.016 1.27)
			(layers "B.Cu" "B.Mask" "B.Paste")
			(net "PVCCIN_CPU0")
		)
		(pad "2" smd rect
			(at -0.889 0)
			(size 1.016 1.27)
			(layers "B.Cu" "B.Mask" "B.Paste")
			(net "GND")
		)
	)
	(footprint ""
		(layer "B.Cu")
		(at 423.799762 -134.19709 180)
		(property "Reference" "PR123"
			(at 0 0 0)
			(layer "B.SilkS")
			(hide yes)
			(effects
				(font
					(size 1.27 1.27)
				)
				(justify mirror)
			)
		)
		(property "Value" ""
			(at 0 0 0)
			(layer "B.Fab")
			(effects
				(font
					(size 1.27 1.27)
				)
				(justify mirror)
			)
		)
		(duplicate_pad_numbers_are_jumpers no)
		(fp_line
			(start 0.7874 0.4064)
			(end 0.7874 -0.4064)
			(stroke
				(width 0.1524)
				(type default)
			)
			(layer "B.SilkS")
		)
		(fp_line
			(start 0.7874 -0.4064)
			(end -0.7874 -0.4064)
			(stroke
				(width 0.1524)
				(type default)
			)
			(layer "B.SilkS")
		)
		(fp_line
			(start -0.7874 0.4064)
			(end 0.7874 0.4064)
			(stroke
				(width 0.1524)
				(type default)
			)
			(layer "B.SilkS")
		)
		(fp_line
			(start -0.7874 -0.4064)
			(end -0.7874 0.4064)
			(stroke
				(width 0.1524)
				(type default)
			)
			(layer "B.SilkS")
		)
		(fp_line
			(start 0.67945 0.3048)
			(end 0.67945 -0.305054)
			(stroke
				(width 0.1)
				(type default)
			)
			(layer "B.Fab")
		)
		(fp_line
			(start 0.67945 -0.305054)
			(end 0.12065 -0.305054)
			(stroke
				(width 0.1)
				(type default)
			)
			(layer "B.Fab")
		)
		(fp_line
			(start 0.12065 0.3048)
			(end 0.67945 0.3048)
			(stroke
				(width 0.1)
				(type default)
			)
			(layer "B.Fab")
		)
		(fp_line
			(start 0.12065 0.2794)
			(end 0.12065 0.3048)
			(stroke
				(width 0.1)
				(type default)
			)
			(layer "B.Fab")
		)
		(fp_line
			(start 0.12065 -0.2794)
			(end -0.12065 -0.2794)
			(stroke
				(width 0.1)
				(type default)
			)
			(layer "B.Fab")
		)
		(fp_line
			(start 0.12065 -0.305054)
			(end 0.12065 -0.2794)
			(stroke
				(width 0.1)
				(type default)
			)
			(layer "B.Fab")
		)
		(fp_line
			(start -0.120396 0.3048)
			(end -0.120396 0.2794)
			(stroke
				(width 0.1)
				(type default)
			)
			(layer "B.Fab")
		)
		(fp_line
			(start -0.120396 0.2794)
			(end 0.12065 0.2794)
			(stroke
				(width 0.1)
				(type default)
			)
			(layer "B.Fab")
		)
		(fp_line
			(start -0.12065 -0.2794)
			(end -0.12065 -0.3048)
			(stroke
				(width 0.1)
				(type default)
			)
			(layer "B.Fab")
		)
		(fp_line
			(start -0.12065 -0.3048)
			(end -0.67945 -0.3048)
			(stroke
				(width 0.1)
				(type default)
			)
			(layer "B.Fab")
		)
		(fp_line
			(start -0.67945 0.3048)
			(end -0.120396 0.3048)
			(stroke
				(width 0.1)
				(type default)
			)
			(layer "B.Fab")
		)
		(fp_line
			(start -0.67945 -0.3048)
			(end -0.67945 0.3048)
			(stroke
				(width 0.1)
				(type default)
			)
			(layer "B.Fab")
		)
		(pad "1" smd circle
			(at 0.40005 0)
			(size 0 0)
			(layers "B.Cu" "B.Mask" "B.Paste")
			(net "PVCCINFAON_CPU0_VIN_CSNIN")
		)
		(pad "2" smd circle
			(at -0.40005 0)
			(size 0 0)
			(layers "B.Cu" "B.Mask" "B.Paste")
			(net "GND")
		)
	)
	(footprint ""
		(layer "B.Cu")
		(at 477.827594 -343.149682)
		(property "Reference" "DB11"
			(at 2.502662 -5.374386 270)
			(unlocked yes)
			(layer "B.SilkS")
			(effects
				(font
					(size 0.7874 0.5842)
					(thickness 0.1524)
				)
				(justify left mirror)
			)
		)
		(property "Value" ""
			(at 0 0 0)
			(layer "B.Fab")
			(effects
				(font
					(size 1.27 1.27)
				)
				(justify mirror)
			)
		)
		(duplicate_pad_numbers_are_jumpers no)
		(fp_line
			(start -3.330702 -4.771136)
			(end 0 4.011168)
			(stroke
				(width 0.1524)
				(type default)
			)
			(layer "B.SilkS")
		)
		(fp_line
			(start 0 4.011168)
			(end 3.330702 -4.771136)
			(stroke
				(width 0.1524)
				(type default)
			)
			(layer "B.SilkS")
		)
		(fp_line
			(start 3.330702 -4.771136)
			(end -3.330702 -4.771136)
			(stroke
				(width 0.1524)
				(type default)
			)
			(layer "B.SilkS")
		)
		(fp_line
			(start -3.330702 -4.771136)
			(end 0 4.011168)
			(stroke
				(width 0.1)
				(type default)
			)
			(layer "B.Fab")
		)
		(fp_line
			(start 0 4.011168)
			(end 3.330702 -4.771136)
			(stroke
				(width 0.1)
				(type default)
			)
			(layer "B.Fab")
		)
		(fp_line
			(start 3.330702 -4.771136)
			(end -3.330702 -4.771136)
			(stroke
				(width 0.1)
				(type default)
			)
			(layer "B.Fab")
		)
		(pad "1" thru_hole circle
			(at 0 0 180)
			(size 2.159 2.159)
			(drill 1.7018)
			(layers "*.Cu" "*.Mask")
			(remove_unused_layers no)
			(net "T1_GND")
			(clearance 0.0254)
			(thermal_gap 0.0254)
		)
		(pad "2" thru_hole circle
			(at 1.27 -3.348736 180)
			(size 2.159 2.159)
			(drill 1.7018)
			(layers "*.Cu" "*.Mask")
			(remove_unused_layers no)
			(net "TDR_SE_50_OHM_IN4")
			(clearance 0.0254)
			(thermal_gap 0.0254)
		)
		(pad "3" thru_hole circle
			(at -1.27 -3.348736 180)
			(size 2.159 2.159)
			(drill 1.7018)
			(layers "*.Cu" "*.Mask")
			(remove_unused_layers no)
			(net "TDR_SE_50_OHM_IN4")
			(clearance 0.0254)
			(thermal_gap 0.0254)
		)
	)
)
